(kicad_pcb
	(version 20260206)
	(generator "pcbnew")
	(generator_version "10.0")
	(general
		(thickness 1.6)
		(legacy_teardrops no)
	)
	(paper "A4")
	(title_block
		(title "01162023_DA0F0TEBIF0_F0T_Expander_BD_F_brd_V02_OCP.brd")
		(comment 1 "Grand Teton / footprint 6602 of 9728 (PEX1), pads 1075-1189 of 2397")
	)
	(layers
		(0 "F.Cu" signal "TOP")
		(4 "In1.Cu" signal "GND")
		(6 "In2.Cu" signal "VCC")
		(8 "In3.Cu" signal "VCC1")
		(10 "In4.Cu" signal "GND1")
		(12 "In5.Cu" signal "IN1")
		(14 "In6.Cu" signal "GND2")
		(16 "In7.Cu" signal "IN2")
		(18 "In8.Cu" signal "GND3")
		(20 "In9.Cu" signal "IN3")
		(22 "In10.Cu" signal "GND4")
		(24 "In11.Cu" signal "IN4")
		(26 "In12.Cu" signal "GND5")
		(28 "In13.Cu" signal "IN5")
		(30 "In14.Cu" signal "GND6")
		(32 "In15.Cu" signal "IN6")
		(34 "In16.Cu" signal "GND7")
		(2 "B.Cu" signal "BOTTOM")
		(9 "F.Adhes" user "F.Adhesive")
		(11 "B.Adhes" user "B.Adhesive")
		(13 "F.Paste" user "Package Geometry/Pastemask Top")
		(15 "B.Paste" user "Package Geometry/Pastemask Bottom")
		(5 "F.SilkS" user "Ref Des/Silkscreen Top")
		(7 "B.SilkS" user "Ref Des/Silkscreen Bottom")
		(1 "F.Mask" user "Board Geometry/Soldermask Top")
		(3 "B.Mask" user "Board Geometry/Soldermask Bottom")
		(17 "Dwgs.User" user "User.Drawings")
		(19 "Cmts.User" user "User.Comments")
		(21 "Eco1.User" user "User.Eco1")
		(23 "Eco2.User" user "User.Eco2")
		(25 "Edge.Cuts" user "Board Geometry/Outline")
		(27 "Margin" user)
		(31 "F.CrtYd" user "Package Geometry/Place Bound Top")
		(29 "B.CrtYd" user "Package Geometry/Place Bound Bottom")
		(35 "F.Fab" user "Ref Des/Assembly Top")
		(33 "B.Fab" user "Ref Des/Assembly Bottom")
	)
	(footprint ""
		(layer "F.Cu")
		(at 175.749966 -295.89984)
		(property "Reference" "PEX1"
			(at -3.353562 35.593274 0)
			(unlocked yes)
			(layer "F.SilkS")
			(effects
				(font
					(size 2.032 1.524)
					(thickness 0.1524)
				)
				(justify left)
			)
		)
		(property "Value" ""
			(at 0 0 0)
			(layer "F.Fab")
			(effects
				(font
					(size 1.27 1.27)
				)
			)
		)
		(duplicate_pad_numbers_are_jumpers no)
		(pad "B48" smd circle
			(at 21.850096 -21.850096)
			(size 0.4572 0.4572)
			(layers "F.Cu" "F.Mask" "F.Paste")
			(net "GND")
		)
		(pad "B49" smd circle
			(at 22.800056 -21.850096)
			(size 0.4572 0.4572)
			(layers "F.Cu" "F.Mask" "F.Paste")
			(net "GND")
		)
		(pad "BA1" smd circle
			(at -22.800056 15.200122)
			(size 0.4572 0.4572)
			(layers "F.Cu" "F.Mask" "F.Paste")
			(net "GND")
		)
		(pad "BA2" smd circle
			(at -21.850096 15.200122)
			(size 0.4572 0.4572)
			(layers "F.Cu" "F.Mask" "F.Paste")
			(net "GND")
		)
		(pad "BA3" smd circle
			(at -20.899882 15.200122)
			(size 0.4572 0.4572)
			(layers "F.Cu" "F.Mask" "F.Paste")
			(net "GND")
		)
		(pad "BA4" smd circle
			(at -19.949922 15.200122)
			(size 0.4572 0.4572)
			(layers "F.Cu" "F.Mask" "F.Paste")
			(net "Net_1664")
		)
		(pad "BA5" smd circle
			(at -18.999962 15.200122)
			(size 0.4572 0.4572)
			(layers "F.Cu" "F.Mask" "F.Paste")
			(net "GND")
		)
		(pad "BA6" smd circle
			(at -18.050002 15.200122)
			(size 0.4572 0.4572)
			(layers "F.Cu" "F.Mask" "F.Paste")
			(net "Net_1680")
		)
		(pad "BA7" smd circle
			(at -17.100042 15.200122)
			(size 0.4572 0.4572)
			(layers "F.Cu" "F.Mask" "F.Paste")
			(net "GND")
		)
		(pad "BA8" smd circle
			(at -16.150082 15.200122)
			(size 0.4572 0.4572)
			(layers "F.Cu" "F.Mask" "F.Paste")
			(net "Net_1641")
		)
		(pad "BA9" smd circle
			(at -15.200122 15.200122)
			(size 0.4572 0.4572)
			(layers "F.Cu" "F.Mask" "F.Paste")
			(net "GND")
		)
		(pad "BA10" smd circle
			(at -14.249908 15.200122)
			(size 0.4572 0.4572)
			(layers "F.Cu" "F.Mask" "F.Paste")
			(net "P5E_PEX1_STN2_TX_DP<46>")
		)
		(pad "BA11" smd circle
			(at -13.299948 15.200122)
			(size 0.4572 0.4572)
			(layers "F.Cu" "F.Mask" "F.Paste")
			(net "GND")
		)
		(pad "BA12" smd circle
			(at -12.349988 15.200122)
			(size 0.4572 0.4572)
			(layers "F.Cu" "F.Mask" "F.Paste")
			(net "P5E_PEX1_STN2_TX_DP<44>")
		)
		(pad "BA13" smd circle
			(at -11.400028 15.200122)
			(size 0.4572 0.4572)
			(layers "F.Cu" "F.Mask" "F.Paste")
			(net "GND")
		)
		(pad "BA14" smd circle
			(at -10.450068 15.200122)
			(size 0.4572 0.4572)
			(layers "F.Cu" "F.Mask" "F.Paste")
			(net "P5E_PEX1_STN2_TX_DP<42>")
		)
		(pad "BA15" smd circle
			(at -9.500108 15.200122)
			(size 0.4572 0.4572)
			(layers "F.Cu" "F.Mask" "F.Paste")
			(net "GND")
		)
		(pad "BA16" smd circle
			(at -8.549894 15.200122)
			(size 0.4572 0.4572)
			(layers "F.Cu" "F.Mask" "F.Paste")
			(net "P5E_PEX1_STN2_TX_DP<40>")
		)
		(pad "BA17" smd circle
			(at -7.599934 15.200122)
			(size 0.4572 0.4572)
			(layers "F.Cu" "F.Mask" "F.Paste")
			(net "GND")
		)
		(pad "BA18" smd circle
			(at -6.649974 15.200122)
			(size 0.4572 0.4572)
			(layers "F.Cu" "F.Mask" "F.Paste")
			(net "P5E_PEX1_STN2_TX_DP<38>")
		)
		(pad "BA19" smd circle
			(at -5.700014 15.200122)
			(size 0.4572 0.4572)
			(layers "F.Cu" "F.Mask" "F.Paste")
			(net "GND")
		)
		(pad "BA20" smd circle
			(at -4.750054 15.200122)
			(size 0.4572 0.4572)
			(layers "F.Cu" "F.Mask" "F.Paste")
			(net "P5E_PEX1_STN2_TX_DP<36>")
		)
		(pad "BA21" smd circle
			(at -3.800094 15.200122)
			(size 0.4572 0.4572)
			(layers "F.Cu" "F.Mask" "F.Paste")
			(net "GND")
		)
		(pad "BA22" smd circle
			(at -2.84988 15.200122)
			(size 0.4572 0.4572)
			(layers "F.Cu" "F.Mask" "F.Paste")
			(net "P5E_PEX1_STN2_TX_DP<34>")
		)
		(pad "BA23" smd circle
			(at -1.89992 15.200122)
			(size 0.4572 0.4572)
			(layers "F.Cu" "F.Mask" "F.Paste")
			(net "GND")
		)
		(pad "BA24" smd circle
			(at -0.94996 15.200122)
			(size 0.4572 0.4572)
			(layers "F.Cu" "F.Mask" "F.Paste")
			(net "P5E_PEX1_STN2_TX_DP<32>")
		)
		(pad "BA25" smd circle
			(at 0 15.200122)
			(size 0.4572 0.4572)
			(layers "F.Cu" "F.Mask" "F.Paste")
			(net "GND")
		)
		(pad "BA26" smd circle
			(at 0.94996 15.200122)
			(size 0.4572 0.4572)
			(layers "F.Cu" "F.Mask" "F.Paste")
			(net "P5E_PEX1_STN1_TX_DN<17>")
		)
		(pad "BA27" smd circle
			(at 1.89992 15.200122)
			(size 0.4572 0.4572)
			(layers "F.Cu" "F.Mask" "F.Paste")
			(net "GND")
		)
		(pad "BA28" smd circle
			(at 2.84988 15.200122)
			(size 0.4572 0.4572)
			(layers "F.Cu" "F.Mask" "F.Paste")
			(net "P5E_PEX1_STN1_TX_DN<19>")
		)
		(pad "BA29" smd circle
			(at 3.800094 15.200122)
			(size 0.4572 0.4572)
			(layers "F.Cu" "F.Mask" "F.Paste")
			(net "GND")
		)
		(pad "BA30" smd circle
			(at 4.750054 15.200122)
			(size 0.4572 0.4572)
			(layers "F.Cu" "F.Mask" "F.Paste")
			(net "P5E_PEX1_STN1_TX_DN<21>")
		)
		(pad "BA31" smd circle
			(at 5.700014 15.200122)
			(size 0.4572 0.4572)
			(layers "F.Cu" "F.Mask" "F.Paste")
			(net "GND")
		)
		(pad "BA32" smd circle
			(at 6.649974 15.200122)
			(size 0.4572 0.4572)
			(layers "F.Cu" "F.Mask" "F.Paste")
			(net "P5E_PEX1_STN1_TX_DN<23>")
		)
		(pad "BA33" smd circle
			(at 7.599934 15.200122)
			(size 0.4572 0.4572)
			(layers "F.Cu" "F.Mask" "F.Paste")
			(net "GND")
		)
		(pad "BA34" smd circle
			(at 8.549894 15.200122)
			(size 0.4572 0.4572)
			(layers "F.Cu" "F.Mask" "F.Paste")
			(net "P5E_PEX1_STN1_TX_DN<25>")
		)
		(pad "BA35" smd circle
			(at 9.500108 15.200122)
			(size 0.4572 0.4572)
			(layers "F.Cu" "F.Mask" "F.Paste")
			(net "GND")
		)
		(pad "BA36" smd circle
			(at 10.450068 15.200122)
			(size 0.4572 0.4572)
			(layers "F.Cu" "F.Mask" "F.Paste")
			(net "P5E_PEX1_STN1_TX_DN<27>")
		)
		(pad "BA37" smd circle
			(at 11.400028 15.200122)
			(size 0.4572 0.4572)
			(layers "F.Cu" "F.Mask" "F.Paste")
			(net "GND")
		)
		(pad "BA38" smd circle
			(at 12.349988 15.200122)
			(size 0.4572 0.4572)
			(layers "F.Cu" "F.Mask" "F.Paste")
			(net "P5E_PEX1_STN1_TX_DN<29>")
		)
		(pad "BA39" smd circle
			(at 13.299948 15.200122)
			(size 0.4572 0.4572)
			(layers "F.Cu" "F.Mask" "F.Paste")
			(net "GND")
		)
		(pad "BA40" smd circle
			(at 14.249908 15.200122)
			(size 0.4572 0.4572)
			(layers "F.Cu" "F.Mask" "F.Paste")
			(net "P5E_PEX1_STN1_TX_DN<31>")
		)
		(pad "BA41" smd circle
			(at 15.200122 15.200122)
			(size 0.4572 0.4572)
			(layers "F.Cu" "F.Mask" "F.Paste")
			(net "GND")
		)
		(pad "BA42" smd circle
			(at 16.150082 15.200122)
			(size 0.4572 0.4572)
			(layers "F.Cu" "F.Mask" "F.Paste")
			(net "P5E_PEX1_STN0_TX_DN<14>")
		)
		(pad "BA43" smd circle
			(at 17.100042 15.200122)
			(size 0.4572 0.4572)
			(layers "F.Cu" "F.Mask" "F.Paste")
			(net "GND")
		)
		(pad "BA44" smd circle
			(at 18.050002 15.200122)
			(size 0.4572 0.4572)
			(layers "F.Cu" "F.Mask" "F.Paste")
			(net "P5E_PEX1_STN0_TX_DN<12>")
		)
		(pad "BA45" smd circle
			(at 18.999962 15.200122)
			(size 0.4572 0.4572)
			(layers "F.Cu" "F.Mask" "F.Paste")
			(net "GND")
		)
		(pad "BA46" smd circle
			(at 19.949922 15.200122)
			(size 0.4572 0.4572)
			(layers "F.Cu" "F.Mask" "F.Paste")
			(net "P5E_PEX1_STN0_TX_DP<10>")
		)
		(pad "BA47" smd circle
			(at 20.899882 15.200122)
			(size 0.4572 0.4572)
			(layers "F.Cu" "F.Mask" "F.Paste")
			(net "GND")
		)
		(pad "BA48" smd circle
			(at 21.850096 15.200122)
			(size 0.4572 0.4572)
			(layers "F.Cu" "F.Mask" "F.Paste")
			(net "GND")
		)
		(pad "BA49" smd circle
			(at 22.800056 15.200122)
			(size 0.4572 0.4572)
			(layers "F.Cu" "F.Mask" "F.Paste")
			(net "GND")
		)
		(pad "BB1" smd circle
			(at -22.800056 16.150082)
			(size 0.4572 0.4572)
			(layers "F.Cu" "F.Mask" "F.Paste")
			(net "Net_1676")
		)
		(pad "BB2" smd circle
			(at -21.850096 16.150082)
			(size 0.4572 0.4572)
			(layers "F.Cu" "F.Mask" "F.Paste")
			(net "Net_1653")
		)
		(pad "BB3" smd circle
			(at -20.899882 16.150082)
			(size 0.4572 0.4572)
			(layers "F.Cu" "F.Mask" "F.Paste")
			(net "GND")
		)
		(pad "BB4" smd circle
			(at -19.949922 16.150082)
			(size 0.4572 0.4572)
			(layers "F.Cu" "F.Mask" "F.Paste")
			(net "Net_1647")
		)
		(pad "BB5" smd circle
			(at -18.999962 16.150082)
			(size 0.4572 0.4572)
			(layers "F.Cu" "F.Mask" "F.Paste")
			(net "GND")
		)
		(pad "BB6" smd circle
			(at -18.050002 16.150082)
			(size 0.4572 0.4572)
			(layers "F.Cu" "F.Mask" "F.Paste")
			(net "Net_1656")
		)
		(pad "BB7" smd circle
			(at -17.100042 16.150082)
			(size 0.4572 0.4572)
			(layers "F.Cu" "F.Mask" "F.Paste")
			(net "GND")
		)
		(pad "BB8" smd circle
			(at -16.150082 16.150082)
			(size 0.4572 0.4572)
			(layers "F.Cu" "F.Mask" "F.Paste")
			(net "Net_1662")
		)
		(pad "BB9" smd circle
			(at -15.200122 16.150082)
			(size 0.4572 0.4572)
			(layers "F.Cu" "F.Mask" "F.Paste")
			(net "GND")
		)
		(pad "BB10" smd circle
			(at -14.249908 16.150082)
			(size 0.4572 0.4572)
			(layers "F.Cu" "F.Mask" "F.Paste")
			(net "P5E_PEX1_STN2_TX_DN<46>")
		)
		(pad "BB11" smd circle
			(at -13.299948 16.150082)
			(size 0.4572 0.4572)
			(layers "F.Cu" "F.Mask" "F.Paste")
			(net "GND")
		)
		(pad "BB12" smd circle
			(at -12.349988 16.150082)
			(size 0.4572 0.4572)
			(layers "F.Cu" "F.Mask" "F.Paste")
			(net "P5E_PEX1_STN2_TX_DN<44>")
		)
		(pad "BB13" smd circle
			(at -11.400028 16.150082)
			(size 0.4572 0.4572)
			(layers "F.Cu" "F.Mask" "F.Paste")
			(net "GND")
		)
		(pad "BB14" smd circle
			(at -10.450068 16.150082)
			(size 0.4572 0.4572)
			(layers "F.Cu" "F.Mask" "F.Paste")
			(net "P5E_PEX1_STN2_TX_DN<42>")
		)
		(pad "BB15" smd circle
			(at -9.500108 16.150082)
			(size 0.4572 0.4572)
			(layers "F.Cu" "F.Mask" "F.Paste")
			(net "GND")
		)
		(pad "BB16" smd circle
			(at -8.549894 16.150082)
			(size 0.4572 0.4572)
			(layers "F.Cu" "F.Mask" "F.Paste")
			(net "P5E_PEX1_STN2_TX_DN<40>")
		)
		(pad "BB17" smd circle
			(at -7.599934 16.150082)
			(size 0.4572 0.4572)
			(layers "F.Cu" "F.Mask" "F.Paste")
			(net "GND")
		)
		(pad "BB18" smd circle
			(at -6.649974 16.150082)
			(size 0.4572 0.4572)
			(layers "F.Cu" "F.Mask" "F.Paste")
			(net "P5E_PEX1_STN2_TX_DN<38>")
		)
		(pad "BB19" smd circle
			(at -5.700014 16.150082)
			(size 0.4572 0.4572)
			(layers "F.Cu" "F.Mask" "F.Paste")
			(net "GND")
		)
		(pad "BB20" smd circle
			(at -4.750054 16.150082)
			(size 0.4572 0.4572)
			(layers "F.Cu" "F.Mask" "F.Paste")
			(net "P5E_PEX1_STN2_TX_DN<36>")
		)
		(pad "BB21" smd circle
			(at -3.800094 16.150082)
			(size 0.4572 0.4572)
			(layers "F.Cu" "F.Mask" "F.Paste")
			(net "GND")
		)
		(pad "BB22" smd circle
			(at -2.84988 16.150082)
			(size 0.4572 0.4572)
			(layers "F.Cu" "F.Mask" "F.Paste")
			(net "P5E_PEX1_STN2_TX_DN<34>")
		)
		(pad "BB23" smd circle
			(at -1.89992 16.150082)
			(size 0.4572 0.4572)
			(layers "F.Cu" "F.Mask" "F.Paste")
			(net "GND")
		)
		(pad "BB24" smd circle
			(at -0.94996 16.150082)
			(size 0.4572 0.4572)
			(layers "F.Cu" "F.Mask" "F.Paste")
			(net "P5E_PEX1_STN2_TX_DN<32>")
		)
		(pad "BB25" smd circle
			(at 0 16.150082)
			(size 0.4572 0.4572)
			(layers "F.Cu" "F.Mask" "F.Paste")
			(net "GND")
		)
		(pad "BB26" smd circle
			(at 0.94996 16.150082)
			(size 0.4572 0.4572)
			(layers "F.Cu" "F.Mask" "F.Paste")
			(net "P5E_PEX1_STN1_TX_DP<17>")
		)
		(pad "BB27" smd circle
			(at 1.89992 16.150082)
			(size 0.4572 0.4572)
			(layers "F.Cu" "F.Mask" "F.Paste")
			(net "GND")
		)
		(pad "BB28" smd circle
			(at 2.84988 16.150082)
			(size 0.4572 0.4572)
			(layers "F.Cu" "F.Mask" "F.Paste")
			(net "P5E_PEX1_STN1_TX_DP<19>")
		)
		(pad "BB29" smd circle
			(at 3.800094 16.150082)
			(size 0.4572 0.4572)
			(layers "F.Cu" "F.Mask" "F.Paste")
			(net "GND")
		)
		(pad "BB30" smd circle
			(at 4.750054 16.150082)
			(size 0.4572 0.4572)
			(layers "F.Cu" "F.Mask" "F.Paste")
			(net "P5E_PEX1_STN1_TX_DP<21>")
		)
		(pad "BB31" smd circle
			(at 5.700014 16.150082)
			(size 0.4572 0.4572)
			(layers "F.Cu" "F.Mask" "F.Paste")
			(net "GND")
		)
		(pad "BB32" smd circle
			(at 6.649974 16.150082)
			(size 0.4572 0.4572)
			(layers "F.Cu" "F.Mask" "F.Paste")
			(net "P5E_PEX1_STN1_TX_DP<23>")
		)
		(pad "BB33" smd circle
			(at 7.599934 16.150082)
			(size 0.4572 0.4572)
			(layers "F.Cu" "F.Mask" "F.Paste")
			(net "GND")
		)
		(pad "BB34" smd circle
			(at 8.549894 16.150082)
			(size 0.4572 0.4572)
			(layers "F.Cu" "F.Mask" "F.Paste")
			(net "P5E_PEX1_STN1_TX_DP<25>")
		)
		(pad "BB35" smd circle
			(at 9.500108 16.150082)
			(size 0.4572 0.4572)
			(layers "F.Cu" "F.Mask" "F.Paste")
			(net "GND")
		)
		(pad "BB36" smd circle
			(at 10.450068 16.150082)
			(size 0.4572 0.4572)
			(layers "F.Cu" "F.Mask" "F.Paste")
			(net "P5E_PEX1_STN1_TX_DP<27>")
		)
		(pad "BB37" smd circle
			(at 11.400028 16.150082)
			(size 0.4572 0.4572)
			(layers "F.Cu" "F.Mask" "F.Paste")
			(net "GND")
		)
		(pad "BB38" smd circle
			(at 12.349988 16.150082)
			(size 0.4572 0.4572)
			(layers "F.Cu" "F.Mask" "F.Paste")
			(net "P5E_PEX1_STN1_TX_DP<29>")
		)
		(pad "BB39" smd circle
			(at 13.299948 16.150082)
			(size 0.4572 0.4572)
			(layers "F.Cu" "F.Mask" "F.Paste")
			(net "GND")
		)
		(pad "BB40" smd circle
			(at 14.249908 16.150082)
			(size 0.4572 0.4572)
			(layers "F.Cu" "F.Mask" "F.Paste")
			(net "P5E_PEX1_STN1_TX_DP<31>")
		)
		(pad "BB41" smd circle
			(at 15.200122 16.150082)
			(size 0.4572 0.4572)
			(layers "F.Cu" "F.Mask" "F.Paste")
			(net "GND")
		)
		(pad "BB42" smd circle
			(at 16.150082 16.150082)
			(size 0.4572 0.4572)
			(layers "F.Cu" "F.Mask" "F.Paste")
			(net "P5E_PEX1_STN0_TX_DP<14>")
		)
		(pad "BB43" smd circle
			(at 17.100042 16.150082)
			(size 0.4572 0.4572)
			(layers "F.Cu" "F.Mask" "F.Paste")
			(net "GND")
		)
		(pad "BB44" smd circle
			(at 18.050002 16.150082)
			(size 0.4572 0.4572)
			(layers "F.Cu" "F.Mask" "F.Paste")
			(net "P5E_PEX1_STN0_TX_DP<12>")
		)
		(pad "BB45" smd circle
			(at 18.999962 16.150082)
			(size 0.4572 0.4572)
			(layers "F.Cu" "F.Mask" "F.Paste")
			(net "GND")
		)
		(pad "BB46" smd circle
			(at 19.949922 16.150082)
			(size 0.4572 0.4572)
			(layers "F.Cu" "F.Mask" "F.Paste")
			(net "P5E_PEX1_STN0_TX_DN<10>")
		)
		(pad "BB47" smd circle
			(at 20.899882 16.150082)
			(size 0.4572 0.4572)
			(layers "F.Cu" "F.Mask" "F.Paste")
			(net "GND")
		)
		(pad "BB48" smd circle
			(at 21.850096 16.150082)
			(size 0.4572 0.4572)
			(layers "F.Cu" "F.Mask" "F.Paste")
			(net "P5E_PEX1_STN0_TX_DP<7>")
		)
		(pad "BB49" smd circle
			(at 22.800056 16.150082)
			(size 0.4572 0.4572)
			(layers "F.Cu" "F.Mask" "F.Paste")
			(net "P5E_PEX1_STN0_TX_DN<7>")
		)
		(pad "BC1" smd circle
			(at -22.800056 17.100042)
			(size 0.4572 0.4572)
			(layers "F.Cu" "F.Mask" "F.Paste")
			(net "GND")
		)
		(pad "BC2" smd circle
			(at -21.850096 17.100042)
			(size 0.4572 0.4572)
			(layers "F.Cu" "F.Mask" "F.Paste")
			(net "GND")
		)
		(pad "BC3" smd circle
			(at -20.899882 17.100042)
			(size 0.4572 0.4572)
			(layers "F.Cu" "F.Mask" "F.Paste")
			(net "Net_1684")
		)
		(pad "BC4" smd circle
			(at -19.949922 17.100042)
			(size 0.4572 0.4572)
			(layers "F.Cu" "F.Mask" "F.Paste")
			(net "GND")
		)
		(pad "BC5" smd circle
			(at -18.999962 17.100042)
			(size 0.4572 0.4572)
			(layers "F.Cu" "F.Mask" "F.Paste")
			(net "Net_1682")
		)
		(pad "BC6" smd circle
			(at -18.050002 17.100042)
			(size 0.4572 0.4572)
			(layers "F.Cu" "F.Mask" "F.Paste")
			(net "GND")
		)
		(pad "BC7" smd circle
			(at -17.100042 17.100042)
			(size 0.4572 0.4572)
			(layers "F.Cu" "F.Mask" "F.Paste")
			(net "Net_1646")
		)
		(pad "BC8" smd circle
			(at -16.150082 17.100042)
			(size 0.4572 0.4572)
			(layers "F.Cu" "F.Mask" "F.Paste")
			(net "GND")
		)
		(pad "BC9" smd circle
			(at -15.200122 17.100042)
			(size 0.4572 0.4572)
			(layers "F.Cu" "F.Mask" "F.Paste")
			(net "P5E_PEX1_STN2_TX_DP<47>")
		)
		(pad "BC10" smd circle
			(at -14.249908 17.100042)
			(size 0.4572 0.4572)
			(layers "F.Cu" "F.Mask" "F.Paste")
			(net "GND")
		)
		(pad "BC11" smd circle
			(at -13.299948 17.100042)
			(size 0.4572 0.4572)
			(layers "F.Cu" "F.Mask" "F.Paste")
			(net "P5E_PEX1_STN2_TX_DP<45>")
		)
		(pad "BC12" smd circle
			(at -12.349988 17.100042)
			(size 0.4572 0.4572)
			(layers "F.Cu" "F.Mask" "F.Paste")
			(net "GND")
		)
		(pad "BC13" smd circle
			(at -11.400028 17.100042)
			(size 0.4572 0.4572)
			(layers "F.Cu" "F.Mask" "F.Paste")
			(net "P5E_PEX1_STN2_TX_DP<43>")
		)
		(pad "BC14" smd circle
			(at -10.450068 17.100042)
			(size 0.4572 0.4572)
			(layers "F.Cu" "F.Mask" "F.Paste")
			(net "GND")
		)
		(pad "BC15" smd circle
			(at -9.500108 17.100042)
			(size 0.4572 0.4572)
			(layers "F.Cu" "F.Mask" "F.Paste")
			(net "P5E_PEX1_STN2_TX_DP<41>")
		)
	)
)
